(kicad_pcb
	(version 20260206)
	(generator "pcbnew")
	(generator_version "10.0")
	(general
		(thickness 1.6)
		(legacy_teardrops no)
	)
	(paper "A4")
	(title_block
		(title "03242023_DA0F0TMBIJ0_F0T_Motherboard_J_brd_V01_OCP.brd")
		(comment 1 "Grand Teton / footprints 1502-1507 of 6105")
	)
	(layers
		(0 "F.Cu" signal "TOP")
		(4 "In1.Cu" signal "GND")
		(6 "In2.Cu" signal "IN1")
		(8 "In3.Cu" signal "GND1")
		(10 "In4.Cu" signal "IN2")
		(12 "In5.Cu" signal "GND2")
		(14 "In6.Cu" signal "IN3")
		(16 "In7.Cu" signal "GND3")
		(18 "In8.Cu" signal "VCC")
		(20 "In9.Cu" signal "VCC1")
		(22 "In10.Cu" signal "GND4")
		(24 "In11.Cu" signal "IN4")
		(26 "In12.Cu" signal "GND5")
		(28 "In13.Cu" signal "IN5")
		(30 "In14.Cu" signal "GND6")
		(32 "In15.Cu" signal "IN6")
		(34 "In16.Cu" signal "GND7")
		(2 "B.Cu" signal "BOTTOM")
		(9 "F.Adhes" user "F.Adhesive")
		(11 "B.Adhes" user "B.Adhesive")
		(13 "F.Paste" user "Package Geometry/Pastemask Top")
		(15 "B.Paste" user "Package Geometry/Pastemask Bottom")
		(5 "F.SilkS" user "Ref Des/Silkscreen Top")
		(7 "B.SilkS" user "Ref Des/Silkscreen Bottom")
		(1 "F.Mask" user "Board Geometry/Soldermask Top")
		(3 "B.Mask" user "Board Geometry/Soldermask Bottom")
		(17 "Dwgs.User" user "User.Drawings")
		(19 "Cmts.User" user "User.Comments")
		(21 "Eco1.User" user "User.Eco1")
		(23 "Eco2.User" user "User.Eco2")
		(25 "Edge.Cuts" user "Board Geometry/Outline")
		(27 "Margin" user)
		(31 "F.CrtYd" user "Package Geometry/Place Bound Top")
		(29 "B.CrtYd" user "Package Geometry/Place Bound Bottom")
		(35 "F.Fab" user "Ref Des/Assembly Top")
		(33 "B.Fab" user "Ref Des/Assembly Bottom")
	)
	(footprint ""
		(layer "F.Cu")
		(at 131.466844 -134.104126 180)
		(property "Reference" "R3395"
			(at 0 0 180)
			(layer "F.SilkS")
			(hide yes)
			(effects
				(font
					(size 1.27 1.27)
				)
			)
		)
		(property "Value" ""
			(at 0 0 180)
			(layer "F.Fab")
			(effects
				(font
					(size 1.27 1.27)
				)
			)
		)
		(duplicate_pad_numbers_are_jumpers no)
		(fp_line
			(start 0.7874 0.4064)
			(end -0.7874 0.4064)
			(stroke
				(width 0.1524)
				(type default)
			)
			(layer "F.SilkS")
		)
		(fp_line
			(start 0.7874 -0.4064)
			(end 0.7874 0.4064)
			(stroke
				(width 0.1524)
				(type default)
			)
			(layer "F.SilkS")
		)
		(fp_line
			(start -0.7874 0.4064)
			(end -0.7874 -0.4064)
			(stroke
				(width 0.1524)
				(type default)
			)
			(layer "F.SilkS")
		)
		(fp_line
			(start -0.7874 -0.4064)
			(end 0.7874 -0.4064)
			(stroke
				(width 0.1524)
				(type default)
			)
			(layer "F.SilkS")
		)
		(fp_line
			(start 0.67945 0.3048)
			(end 0.120396 0.3048)
			(stroke
				(width 0.1)
				(type default)
			)
			(layer "F.Fab")
		)
		(fp_line
			(start 0.67945 -0.3048)
			(end 0.67945 0.3048)
			(stroke
				(width 0.1)
				(type default)
			)
			(layer "F.Fab")
		)
		(fp_line
			(start 0.12065 -0.2794)
			(end 0.12065 -0.3048)
			(stroke
				(width 0.1)
				(type default)
			)
			(layer "F.Fab")
		)
		(fp_line
			(start 0.12065 -0.3048)
			(end 0.67945 -0.3048)
			(stroke
				(width 0.1)
				(type default)
			)
			(layer "F.Fab")
		)
		(fp_line
			(start 0.120396 0.3048)
			(end 0.120396 0.2794)
			(stroke
				(width 0.1)
				(type default)
			)
			(layer "F.Fab")
		)
		(fp_line
			(start 0.120396 0.2794)
			(end -0.12065 0.2794)
			(stroke
				(width 0.1)
				(type default)
			)
			(layer "F.Fab")
		)
		(fp_line
			(start -0.12065 0.3048)
			(end -0.67945 0.3048)
			(stroke
				(width 0.1)
				(type default)
			)
			(layer "F.Fab")
		)
		(fp_line
			(start -0.12065 0.2794)
			(end -0.12065 0.3048)
			(stroke
				(width 0.1)
				(type default)
			)
			(layer "F.Fab")
		)
		(fp_line
			(start -0.12065 -0.2794)
			(end 0.12065 -0.2794)
			(stroke
				(width 0.1)
				(type default)
			)
			(layer "F.Fab")
		)
		(fp_line
			(start -0.12065 -0.305054)
			(end -0.12065 -0.2794)
			(stroke
				(width 0.1)
				(type default)
			)
			(layer "F.Fab")
		)
		(fp_line
			(start -0.67945 0.3048)
			(end -0.67945 -0.305054)
			(stroke
				(width 0.1)
				(type default)
			)
			(layer "F.Fab")
		)
		(fp_line
			(start -0.67945 -0.305054)
			(end -0.12065 -0.305054)
			(stroke
				(width 0.1)
				(type default)
			)
			(layer "F.Fab")
		)
		(pad "1" smd circle
			(at -0.40005 0 180)
			(size 0 0)
			(layers "F.Cu" "F.Mask" "F.Paste")
			(net "P3V3_AUX")
		)
		(pad "2" smd circle
			(at 0.40005 0 180)
			(size 0 0)
			(layers "F.Cu" "F.Mask" "F.Paste")
			(net "SMB_INA230_3V3AUX_SCL")
		)
	)
	(footprint ""
		(layer "F.Cu")
		(at 446.694814 -110.038134)
		(property "Reference" "R1129"
			(at 0 0 0)
			(layer "F.SilkS")
			(hide yes)
			(effects
				(font
					(size 1.27 1.27)
				)
			)
		)
		(property "Value" ""
			(at 0 0 0)
			(layer "F.Fab")
			(effects
				(font
					(size 1.27 1.27)
				)
			)
		)
		(duplicate_pad_numbers_are_jumpers no)
		(fp_line
			(start -0.7874 -0.4064)
			(end 0.7874 -0.4064)
			(stroke
				(width 0.1524)
				(type default)
			)
			(layer "F.SilkS")
		)
		(fp_line
			(start -0.7874 0.4064)
			(end -0.7874 -0.4064)
			(stroke
				(width 0.1524)
				(type default)
			)
			(layer "F.SilkS")
		)
		(fp_line
			(start 0.7874 -0.4064)
			(end 0.7874 0.4064)
			(stroke
				(width 0.1524)
				(type default)
			)
			(layer "F.SilkS")
		)
		(fp_line
			(start 0.7874 0.4064)
			(end -0.7874 0.4064)
			(stroke
				(width 0.1524)
				(type default)
			)
			(layer "F.SilkS")
		)
		(fp_line
			(start -0.67945 -0.305054)
			(end -0.12065 -0.305054)
			(stroke
				(width 0.1)
				(type default)
			)
			(layer "F.Fab")
		)
		(fp_line
			(start -0.67945 0.3048)
			(end -0.67945 -0.305054)
			(stroke
				(width 0.1)
				(type default)
			)
			(layer "F.Fab")
		)
		(fp_line
			(start -0.12065 -0.305054)
			(end -0.12065 -0.2794)
			(stroke
				(width 0.1)
				(type default)
			)
			(layer "F.Fab")
		)
		(fp_line
			(start -0.12065 -0.2794)
			(end 0.12065 -0.2794)
			(stroke
				(width 0.1)
				(type default)
			)
			(layer "F.Fab")
		)
		(fp_line
			(start -0.12065 0.2794)
			(end -0.12065 0.3048)
			(stroke
				(width 0.1)
				(type default)
			)
			(layer "F.Fab")
		)
		(fp_line
			(start -0.12065 0.3048)
			(end -0.67945 0.3048)
			(stroke
				(width 0.1)
				(type default)
			)
			(layer "F.Fab")
		)
		(fp_line
			(start 0.120396 0.2794)
			(end -0.12065 0.2794)
			(stroke
				(width 0.1)
				(type default)
			)
			(layer "F.Fab")
		)
		(fp_line
			(start 0.120396 0.3048)
			(end 0.120396 0.2794)
			(stroke
				(width 0.1)
				(type default)
			)
			(layer "F.Fab")
		)
		(fp_line
			(start 0.12065 -0.3048)
			(end 0.67945 -0.3048)
			(stroke
				(width 0.1)
				(type default)
			)
			(layer "F.Fab")
		)
		(fp_line
			(start 0.12065 -0.2794)
			(end 0.12065 -0.3048)
			(stroke
				(width 0.1)
				(type default)
			)
			(layer "F.Fab")
		)
		(fp_line
			(start 0.67945 -0.3048)
			(end 0.67945 0.3048)
			(stroke
				(width 0.1)
				(type default)
			)
			(layer "F.Fab")
		)
		(fp_line
			(start 0.67945 0.3048)
			(end 0.120396 0.3048)
			(stroke
				(width 0.1)
				(type default)
			)
			(layer "F.Fab")
		)
		(pad "1" smd circle
			(at -0.40005 0)
			(size 0 0)
			(layers "F.Cu" "F.Mask" "F.Paste")
			(net "P3V3_AUX")
		)
		(pad "2" smd circle
			(at 0.40005 0)
			(size 0 0)
			(layers "F.Cu" "F.Mask" "F.Paste")
			(net "HP_LVC3_OCP_V3_1_PRSNT2")
		)
	)
	(footprint ""
		(layer "F.Cu")
		(at 193.93408 -353.761548)
		(property "Reference" "R630"
			(at 0 0 0)
			(layer "F.SilkS")
			(hide yes)
			(effects
				(font
					(size 1.27 1.27)
				)
			)
		)
		(property "Value" ""
			(at 0 0 0)
			(layer "F.Fab")
			(effects
				(font
					(size 1.27 1.27)
				)
			)
		)
		(duplicate_pad_numbers_are_jumpers no)
		(fp_line
			(start -0.7874 -0.4064)
			(end 0.7874 -0.4064)
			(stroke
				(width 0.1524)
				(type default)
			)
			(layer "F.SilkS")
		)
		(fp_line
			(start -0.7874 0.4064)
			(end -0.7874 -0.4064)
			(stroke
				(width 0.1524)
				(type default)
			)
			(layer "F.SilkS")
		)
		(fp_line
			(start 0.7874 -0.4064)
			(end 0.7874 0.4064)
			(stroke
				(width 0.1524)
				(type default)
			)
			(layer "F.SilkS")
		)
		(fp_line
			(start 0.7874 0.4064)
			(end -0.7874 0.4064)
			(stroke
				(width 0.1524)
				(type default)
			)
			(layer "F.SilkS")
		)
		(fp_line
			(start -0.67945 -0.305054)
			(end -0.12065 -0.305054)
			(stroke
				(width 0.1)
				(type default)
			)
			(layer "F.Fab")
		)
		(fp_line
			(start -0.67945 0.3048)
			(end -0.67945 -0.305054)
			(stroke
				(width 0.1)
				(type default)
			)
			(layer "F.Fab")
		)
		(fp_line
			(start -0.12065 -0.305054)
			(end -0.12065 -0.2794)
			(stroke
				(width 0.1)
				(type default)
			)
			(layer "F.Fab")
		)
		(fp_line
			(start -0.12065 -0.2794)
			(end 0.12065 -0.2794)
			(stroke
				(width 0.1)
				(type default)
			)
			(layer "F.Fab")
		)
		(fp_line
			(start -0.12065 0.2794)
			(end -0.12065 0.3048)
			(stroke
				(width 0.1)
				(type default)
			)
			(layer "F.Fab")
		)
		(fp_line
			(start -0.12065 0.3048)
			(end -0.67945 0.3048)
			(stroke
				(width 0.1)
				(type default)
			)
			(layer "F.Fab")
		)
		(fp_line
			(start 0.120396 0.2794)
			(end -0.12065 0.2794)
			(stroke
				(width 0.1)
				(type default)
			)
			(layer "F.Fab")
		)
		(fp_line
			(start 0.120396 0.3048)
			(end 0.120396 0.2794)
			(stroke
				(width 0.1)
				(type default)
			)
			(layer "F.Fab")
		)
		(fp_line
			(start 0.12065 -0.3048)
			(end 0.67945 -0.3048)
			(stroke
				(width 0.1)
				(type default)
			)
			(layer "F.Fab")
		)
		(fp_line
			(start 0.12065 -0.2794)
			(end 0.12065 -0.3048)
			(stroke
				(width 0.1)
				(type default)
			)
			(layer "F.Fab")
		)
		(fp_line
			(start 0.67945 -0.3048)
			(end 0.67945 0.3048)
			(stroke
				(width 0.1)
				(type default)
			)
			(layer "F.Fab")
		)
		(fp_line
			(start 0.67945 0.3048)
			(end 0.120396 0.3048)
			(stroke
				(width 0.1)
				(type default)
			)
			(layer "F.Fab")
		)
		(pad "1" smd circle
			(at -0.40005 0)
			(size 0 0)
			(layers "F.Cu" "F.Mask" "F.Paste")
			(net "PU_PIROM_CPU1_ADDR0")
		)
		(pad "2" smd circle
			(at 0.40005 0)
			(size 0 0)
			(layers "F.Cu" "F.Mask" "F.Paste")
			(net "GND")
		)
	)
	(footprint ""
		(layer "F.Cu")
		(at 67.248278 -402.371052 -90)
		(property "Reference" "C723"
			(at 0 0 270)
			(layer "F.SilkS")
			(hide yes)
			(effects
				(font
					(size 1.27 1.27)
				)
			)
		)
		(property "Value" ""
			(at 0 0 270)
			(layer "F.Fab")
			(effects
				(font
					(size 1.27 1.27)
				)
			)
		)
		(duplicate_pad_numbers_are_jumpers no)
		(fp_line
			(start -0.299974 0.150114)
			(end -0.299974 -0.150114)
			(stroke
				(width 0.1)
				(type default)
			)
			(layer "F.Fab")
		)
		(fp_line
			(start 0.299974 0.150114)
			(end -0.299974 0.150114)
			(stroke
				(width 0.1)
				(type default)
			)
			(layer "F.Fab")
		)
		(fp_line
			(start -0.299974 -0.150114)
			(end 0.299974 -0.150114)
			(stroke
				(width 0.1)
				(type default)
			)
			(layer "F.Fab")
		)
		(fp_line
			(start 0.299974 -0.150114)
			(end 0.299974 0.150114)
			(stroke
				(width 0.1)
				(type default)
			)
			(layer "F.Fab")
		)
		(pad "1" smd rect
			(at -0.2667 0 270)
			(size 0.3048 0.381)
			(layers "F.Cu" "F.Mask" "F.Paste")
			(net "P5E_CPU1_PE0_TX_C_DP<9>")
		)
		(pad "2" smd rect
			(at 0.2667 0 270)
			(size 0.3048 0.381)
			(layers "F.Cu" "F.Mask" "F.Paste")
			(net "P5E_CPU1_PE0_TX_DP<9>")
		)
	)
	(footprint ""
		(layer "F.Cu")
		(at 403.987 -50.637948 180)
		(property "Reference" "R4503"
			(at 0 0 180)
			(layer "F.SilkS")
			(hide yes)
			(effects
				(font
					(size 1.27 1.27)
				)
			)
		)
		(property "Value" ""
			(at 0 0 180)
			(layer "F.Fab")
			(effects
				(font
					(size 1.27 1.27)
				)
			)
		)
		(duplicate_pad_numbers_are_jumpers no)
		(fp_line
			(start 0.7874 0.4064)
			(end -0.7874 0.4064)
			(stroke
				(width 0.1524)
				(type default)
			)
			(layer "F.SilkS")
		)
		(fp_line
			(start 0.7874 -0.4064)
			(end 0.7874 0.4064)
			(stroke
				(width 0.1524)
				(type default)
			)
			(layer "F.SilkS")
		)
		(fp_line
			(start -0.7874 0.4064)
			(end -0.7874 -0.4064)
			(stroke
				(width 0.1524)
				(type default)
			)
			(layer "F.SilkS")
		)
		(fp_line
			(start -0.7874 -0.4064)
			(end 0.7874 -0.4064)
			(stroke
				(width 0.1524)
				(type default)
			)
			(layer "F.SilkS")
		)
		(fp_line
			(start 0.67945 0.3048)
			(end 0.120396 0.3048)
			(stroke
				(width 0.1)
				(type default)
			)
			(layer "F.Fab")
		)
		(fp_line
			(start 0.67945 -0.3048)
			(end 0.67945 0.3048)
			(stroke
				(width 0.1)
				(type default)
			)
			(layer "F.Fab")
		)
		(fp_line
			(start 0.12065 -0.2794)
			(end 0.12065 -0.3048)
			(stroke
				(width 0.1)
				(type default)
			)
			(layer "F.Fab")
		)
		(fp_line
			(start 0.12065 -0.3048)
			(end 0.67945 -0.3048)
			(stroke
				(width 0.1)
				(type default)
			)
			(layer "F.Fab")
		)
		(fp_line
			(start 0.120396 0.3048)
			(end 0.120396 0.2794)
			(stroke
				(width 0.1)
				(type default)
			)
			(layer "F.Fab")
		)
		(fp_line
			(start 0.120396 0.2794)
			(end -0.12065 0.2794)
			(stroke
				(width 0.1)
				(type default)
			)
			(layer "F.Fab")
		)
		(fp_line
			(start -0.12065 0.3048)
			(end -0.67945 0.3048)
			(stroke
				(width 0.1)
				(type default)
			)
			(layer "F.Fab")
		)
		(fp_line
			(start -0.12065 0.2794)
			(end -0.12065 0.3048)
			(stroke
				(width 0.1)
				(type default)
			)
			(layer "F.Fab")
		)
		(fp_line
			(start -0.12065 -0.2794)
			(end 0.12065 -0.2794)
			(stroke
				(width 0.1)
				(type default)
			)
			(layer "F.Fab")
		)
		(fp_line
			(start -0.12065 -0.305054)
			(end -0.12065 -0.2794)
			(stroke
				(width 0.1)
				(type default)
			)
			(layer "F.Fab")
		)
		(fp_line
			(start -0.67945 0.3048)
			(end -0.67945 -0.305054)
			(stroke
				(width 0.1)
				(type default)
			)
			(layer "F.Fab")
		)
		(fp_line
			(start -0.67945 -0.305054)
			(end -0.12065 -0.305054)
			(stroke
				(width 0.1)
				(type default)
			)
			(layer "F.Fab")
		)
		(pad "1" smd circle
			(at -0.40005 0 180)
			(size 0 0)
			(layers "F.Cu" "F.Mask" "F.Paste")
			(net "SMB_HOST_3V3AUX_SDA_R4")
		)
		(pad "2" smd circle
			(at 0.40005 0 180)
			(size 0 0)
			(layers "F.Cu" "F.Mask" "F.Paste")
			(net "SMB_HOST_3V3AUX_XDP_R_SDA")
		)
	)
	(footprint ""
		(layer "F.Cu")
		(at 54.96433 -16.099536 90)
		(property "Reference" "C835"
			(at 0 0 90)
			(layer "F.SilkS")
			(hide yes)
			(effects
				(font
					(size 1.27 1.27)
				)
			)
		)
		(property "Value" ""
			(at 0 0 90)
			(layer "F.Fab")
			(effects
				(font
					(size 1.27 1.27)
				)
			)
		)
		(duplicate_pad_numbers_are_jumpers no)
		(fp_line
			(start 0.299974 -0.150114)
			(end 0.299974 0.150114)
			(stroke
				(width 0.1)
				(type default)
			)
			(layer "F.Fab")
		)
		(fp_line
			(start -0.299974 -0.150114)
			(end 0.299974 -0.150114)
			(stroke
				(width 0.1)
				(type default)
			)
			(layer "F.Fab")
		)
		(fp_line
			(start 0.299974 0.150114)
			(end -0.299974 0.150114)
			(stroke
				(width 0.1)
				(type default)
			)
			(layer "F.Fab")
		)
		(fp_line
			(start -0.299974 0.150114)
			(end -0.299974 -0.150114)
			(stroke
				(width 0.1)
				(type default)
			)
			(layer "F.Fab")
		)
		(pad "1" smd rect
			(at -0.2667 0 90)
			(size 0.3048 0.381)
			(layers "F.Cu" "F.Mask" "F.Paste")
			(net "P5E_CPU1_PE1_TX_C_DP<1>")
		)
		(pad "2" smd rect
			(at 0.2667 0 90)
			(size 0.3048 0.381)
			(layers "F.Cu" "F.Mask" "F.Paste")
			(net "P5E_CPU1_PE1_TX_DP<1>")
		)
	)
)
